FILE_TYPE = CONNECTIVITY;
{Allegro Design Entry HDL 16.6-p007 (v16-6-112F) 10/10/2012}
"PAGE_NUMBER" = 39;
0"NC";
1"PVCCMCP_CPU0\g";
2"PVCCMCP_CPU0\g";
3"PVCCMCP_CPU0\g";
4"PVCCIO_CPU0\g";
5"TP_CPU0_RSVD_12";
6"VSENSE_PVCCIO_CPU0_SKT_VRTN";
7"VSENSE_PVCCIO_CPU0_SKT_VSEN";
8"PD_CPU0_MCP01_DMON";
9"TP_CPU0_RSVD_32";
10"TP_CPU0_RSVD_33";
11"TP_CPU0_RSVD_34";
12"TP_CPU0_RSVD_61";
13"TP_CPU0_KTI2_DFX_DN";
14"TP_CPU0_RSVD_64";
15"TP_CPU0_RSVD_66";
16"TP_CPU0_RSVD_67";
17"TP_CPU0_RSVD_69";
18"TP_CPU0_RSVD_70";
19"TP_CPU0_RSVD_72";
20"TP_CPU0_RSVD_73";
21"VSENSE_PVCCIOMCP_CPU0_SKT_VRTN";
22"VSENSE_PVCCIOMCP_CPU0_SKT_VSEN";
23"VSENSE_PVCCMCP_CPU0_SKT_VRTN";
24"VSENSE_PVSA_CPU0_SKT_VRTN";
25"VSENSE_PVSA_CPU0_SKT_VSEN";
26"TP_CPU0_KTI2_AMONV";
27"VSENSE_PVCCMCP_CPU0_SKT_VSEN";
28"TP_CPU0_RSVD_13";
29"TP_CPU0_RSVD_43";
30"TP_CPU0_RSVD_0";
31"TP_CPU0_RSVD_1";
32"TP_CPU0_RSVD_2";
33"TP_CPU0_RSVD_3";
34"TP_CPU0_RSVD_4";
35"TP_CPU0_RSVD_5";
36"TP_CPU0_RSVD_6";
37"TP_CPU0_RSVD_7";
38"TP_CPU0_RSVD_8";
39"TP_CPU0_RSVD_9";
40"TP_CPU0_RSVD_10";
41"TP_CPU0_RSVD_11";
42"TP_CPU0_RSVD_14";
43"TP_CPU0_RSVD_15";
44"TP_CPU0_RSVD_16";
45"TP_CPU0_RSVD_17";
46"TP_CPU0_RSVD_18";
47"TP_CPU0_RSVD_19";
48"TP_CPU0_RSVD_20";
49"TP_CPU0_RSVD_21";
50"TP_CPU0_RSVD_22";
51"TP_CPU0_RSVD_23";
52"TP_CPU0_RSVD_24";
53"TP_CPU0_RSVD_25";
54"TP_CPU0_RSVD_26";
55"TP_CPU0_RSVD_27";
56"TP_CPU0_RSVD_28";
57"TP_CPU0_RSVD_29";
58"TP_CPU0_RSVD_30";
59"TP_CPU0_RSVD_31";
60"TP_CPU0_RSVD_35";
61"TP_CPU0_RSVD_36";
62"TP_CPU0_RSVD_37";
63"TP_CPU0_RSVD_38";
64"TP_CPU0_RSVD_39";
65"TP_CPU0_RSVD_40";
66"TP_CPU0_RSVD_41";
67"TP_CPU0_RSVD_42";
68"TP_CPU0_RSVD_44";
69"TP_CPU0_RSVD_45";
70"TP_CPU0_RSVD_46";
71"TP_CPU0_RSVD_47";
72"TP_CPU0_RSVD_48";
73"TP_CPU0_RSVD_49";
74"TP_CPU0_RSVD_50";
75"TP_CPU0_RSVD_51";
76"TP_CPU0_RSVD_53";
77"TP_CPU0_RSVD_54";
78"TP_CPU0_RSVD_55";
79"TP_CPU0_RSVD_56";
80"TP_CPU0_RSVD_57";
81"TP_CPU0_RSVD_59";
82"TP_CPU0_RSVD_60";
%"VCC_CORE"
"1","(-2250,4025)","0","mstr_symbols","I123";
;
HDL_POWER"PVCCMCP_CPU0"
CDS_LIB"mstr_symbols";
"A"1;
%"VCC_CORE"
"1","(-6500,2900)","0","mstr_symbols","I125";
;
HDL_POWER"PVCCMCP_CPU0"
CDS_LIB"mstr_symbols";
"A"2;
%"VCC_CORE"
"1","(-7100,1950)","0","mstr_symbols","I126";
;
HDL_POWER"PVCCMCP_CPU0"
CDS_LIB"mstr_symbols";
"A"3;
%"SKX_EXT_B"
"22","(-4250,2550)","0","chpset_lib","I127";
;
CDS_SEC"22"
LOCATION"U5D1"
PART_NUMBER"TBD"
MATERIAL"IC"
PACK_TYPE"BGA1"
SEC_TYPE"BGA1"
CDS_LIB"chpset_lib"
SEC"22"
CDS_LOCATION"U5D1"
ROOM"CPU0";
"VSS_VCCSA_SENSE"
$PN"CG76"24;
"VSS_VCCIO_SENSE"
$PN"BF5"6;
"VCCSA_SENSE"
$PN"CE76"25;
"VCCIO_SENSE"
$PN"BH5"7;
"VCCIO<0>"
$PN"EE10"4;
"VCCIO<1>"
$PN"AE10"4;
"VCCIO<2>"
$PN"AF5"4;
"VCCIO<3>"
$PN"DV11"4;
"VCCIO<4>"
$PN"AM5"4;
"VCCIO<5>"
$PN"AT5"4;
"VCCIO<6>"
$PN"AT7"4;
"VCCIO<7>"
$PN"BE24"4;
"VCCIO<8>"
$PN"DK21"4;
"VCCIO<9>"
$PN"CF5"4;
"VCCIO<10>"
$PN"CG14"4;
"VCCIO<11>"
$PN"CL20"4;
"VCCIO<12>"
$PN"CP13"4;
"VCCIO<13>"
$PN"DE14"4;
"VCCIO<14>"
$PN"DC18"4;
"VCCIO<15>"
$PN"CY17"4;
"VCCIO<16>"
$PN"CU18"4;
"VCCIO<17>"
$PN"CV21"4;
"VCCIO<18>"
$PN"CU12"4;
"VCCIO<19>"
$PN"CN6"4;
"RSVD<0>"
$PN"EF83"30;
"RSVD<1>"
$PN"EF81"31;
"RSVD<2>"
$PN"EF77"32;
"RSVD<3>"
$PN"EF47"33;
"RSVD<4>"
$PN"EE84"34;
"RSVD<5>"
$PN"EE82"35;
"RSVD<6>"
$PN"EE6"36;
"RSVD<7>"
$PN"EE46"37;
"RSVD<8>"
$PN"EE16"38;
"RSVD<9>"
$PN"ED83"39;
"RSVD<10>"
$PN"ED5"40;
"RSVD<11>"
$PN"ED45"41;
"RSVD<12>"
$PN"EC84"5;
"RSVD<13>"
$PN"EC44"28;
"RSVD<14>"
$PN"EC4"42;
"RSVD<15>"
$PN"EC16"43;
"RSVD<16>"
$PN"EB85"44;
"RSVD<17>"
$PN"EB5"45;
"RSVD<18>"
$PN"EB3"46;
"RSVD<19>"
$PN"EA44"47;
"RSVD<20>"
$PN"EA4"48;
"RSVD<21>"
$PN"DY3"49;
"RSVD<22>"
$PN"DW46"50;
"RSVD<23>"
$PN"DW44"51;
"RSVD<24>"
$PN"DV71"52;
"RSVD<25>"
$PN"DV61"53;
"RSVD<26>"
$PN"DU44"54;
"RSVD<27>"
$PN"DT71"55;
"RSVD<28>"
$PN"DR44"56;
"RSVD<29>"
$PN"DP65"57;
"RSVD<30>"
$PN"DP17"58;
"RSVD<31>"
$PN"DN66"59;
"RSVD<32>"
$PN"DN62"9;
"RSVD<33>"
$PN"DM67"10;
"RSVD<34>"
$PN"DL66"11;
"RSVD<35>"
$PN"DL38"60;
"RSVD<36>"
$PN"DK67"61;
"RSVD<37>"
$PN"DK65"62;
"RSVD<38>"
$PN"DK37"63;
"RSVD<39>"
$PN"DK15"64;
"RSVD<40>"
$PN"DJ66"65;
"RSVD<41>"
$PN"DJ36"66;
"RSVD<42>"
$PN"DH65"67;
"RSVD<43>"
$PN"DG64"29;
"RSVD<44>"
$PN"DG36"68;
"RSVD<45>"
$PN"DD51"69;
"RSVD<46>"
$PN"DC52"70;
"RSVD<47>"
$PN"DC46"71;
"RSVD<48>"
$PN"DA56"72;
"RSVD<49>"
$PN"DA54"73;
"RSVD<50>"
$PN"DA52"74;
"RSVD<51>"
$PN"DA40"75;
"RSVD<52>"
$PN"DA24"1;
"RSVD<53>"
$PN"CY73"76;
"RSVD<54>"
$PN"CY63"77;
"RSVD<55>"
$PN"CY57"78;
"RSVD<56>"
$PN"CY53"79;
"RSVD<57>"
$PN"CY39"80;
"RSVD<58>"
$PN"CY25"1;
"RSVD<59>"
$PN"CY23"81;
"RSVD<60>"
$PN"CW62"82;
"RSVD<61>"
$PN"CW60"12;
"RSVD<62>"
$PN"CW24"3;
"RSVD<63>"
$PN"CW22"13;
"RSVD<64>"
$PN"CV69"14;
"RSVD<65>"
$PN"CV23"3;
"RSVD<66>"
$PN"CU60"15;
"RSVD<67>"
$PN"CU6"16;
"RSVD<68>"
$PN"CU24"3;
"RSVD<69>"
$PN"CT69"17;
"RSVD<70>"
$PN"CT5"18;
"RSVD<71>"
$PN"CT23"3;
"RSVD<72>"
$PN"CR60"19;
"RSVD<73>"
$PN"CP31"20;
"RSVD<74>"
$PN"CP23"3;
"RSVD<75>"
$PN"CN28"8;
"RSVD<76>"
$PN"CN24"2;
"RSVD<77>"
$PN"CN22"26;
"RSVD<78>"
$PN"CM25"2;
"RSVD<79>"
$PN"CM23"2;
"RSVD<80>"
$PN"CL26"2;
"CD_VSS_VCC_CORE_SENSE"
$PN"BL16"23;
"CD_VCC_CORE_SENSE"
$PN"BN16"27;
"CD_VCCP_SENSE<0>"
$PN"BU16"21;
"CD_VCCP_SENSE<1>"
$PN"BT17"22;
%"PVCCIO_CPU0"
"1","(-5650,4175)","0","mstr_symbols","I23";
;
VOLTAGE"1.1V"
CDS_LIB"mstr_symbols"
BODY_TYPE"PLUMBING"
HDL_POWER"PVCCIO_CPU0";
"G\NAC"4;
END.
